# S9S_MB_2U (Grand Teton) — schematic netlist excerpt (pin names and nets, part order shuffled) for the footprints in the layout excerpt that follows; sources: Cadence DE-HDL packaged netlist, KiCad conversion of 03242023_DA0F0TMBIJ0_F0T_Motherboard_J_brd_V01_OCP.brd

PU77_P1_3  ISL99390FRZTR5935  ISL99390FRZ-TR5935 IC  pkg QFN21_6X5XB  page 290
  VOS  = PVCCFA_EHV_FIVRA_CPU1_VOS3
  AGND  = GND
  VCC  = PVCCFA_EHV_FIVRA_CPU1_VDD3
  PVCC  = PVCCFA_EHV_FIVRA_CPU1_PVCC1
  PGND1  = GND
  GL1  = NC
  PGND2  = GND
  SW  = SW_PVCCFA_EHV_FIVRA_CPU1_SW3
  VIN1  = SW_P12V_PVCCFA_EHV_FIVRA_CPU1_R
  VIN2  = SW_P12V_PVCCFA_EHV_FIVRA_CPU1_R
  DNC  = NC
  PHASE  = SW_PVCCFA_EHV_FIVRA_CPU1_BOOTR3
  BOOT  = SW_PVCCFA_EHV_FIVRA_CPU1_BOOT3
  PWM  = PVCCFA_EHV_FIVRA_CPU1_PWM3
  EN  = PVCCFA_EHV_FIVRA_CPU1_VDD3
  TOUT_FLT  = PVCCFA_EHV_FIVRA_CPU1_BTSEN
  LSET  = PVCCFA_EHV_FIVRA_CPU1_LSET3
  IOUT  = PVCCFA_EHV_FIVRA_CPU1_IMON3
  REFIN  = PVCCIN_CPU1_VREF
  PGND3  = GND
  GL2  = NC

(kicad_pcb
	(version 20260206)
	(generator "pcbnew")
	(generator_version "10.0")
	(general
		(thickness 1.6)
		(legacy_teardrops no)
	)
	(paper "A4")
	(title_block
		(title "03242023_DA0F0TMBIJ0_F0T_Motherboard_J_brd_V01_OCP.brd")
		(comment 1 "Grand Teton / footprints 351-351 of 6105")
	)
	(layers
		(0 "F.Cu" signal "TOP")
		(4 "In1.Cu" signal "GND")
		(6 "In2.Cu" signal "IN1")
		(8 "In3.Cu" signal "GND1")
		(10 "In4.Cu" signal "IN2")
		(12 "In5.Cu" signal "GND2")
		(14 "In6.Cu" signal "IN3")
		(16 "In7.Cu" signal "GND3")
		(18 "In8.Cu" signal "VCC")
		(20 "In9.Cu" signal "VCC1")
		(22 "In10.Cu" signal "GND4")
		(24 "In11.Cu" signal "IN4")
		(26 "In12.Cu" signal "GND5")
		(28 "In13.Cu" signal "IN5")
		(30 "In14.Cu" signal "GND6")
		(32 "In15.Cu" signal "IN6")
		(34 "In16.Cu" signal "GND7")
		(2 "B.Cu" signal "BOTTOM")
		(9 "F.Adhes" user "F.Adhesive")
		(11 "B.Adhes" user "B.Adhesive")
		(13 "F.Paste" user "Package Geometry/Pastemask Top")
		(15 "B.Paste" user "Package Geometry/Pastemask Bottom")
		(5 "F.SilkS" user "Ref Des/Silkscreen Top")
		(7 "B.SilkS" user "Ref Des/Silkscreen Bottom")
		(1 "F.Mask" user "Board Geometry/Soldermask Top")
		(3 "B.Mask" user "Board Geometry/Soldermask Bottom")
		(17 "Dwgs.User" user "User.Drawings")
		(19 "Cmts.User" user "User.Comments")
		(21 "Eco1.User" user "User.Eco1")
		(23 "Eco2.User" user "User.Eco2")
		(25 "Edge.Cuts" user "Board Geometry/Outline")
		(27 "Margin" user)
		(31 "F.CrtYd" user "Package Geometry/Place Bound Top")
		(29 "B.CrtYd" user "Package Geometry/Place Bound Bottom")
		(35 "F.Fab" user "Ref Des/Assembly Top")
		(33 "B.Fab" user "Ref Des/Assembly Bottom")
	)
	(footprint ""
		(layer "F.Cu")
		(at 181.712616 -353.554284)
		(property "Reference" "PU77_P1_3"
			(at 3.717544 -10.170414 0)
			(unlocked yes)
			(layer "F.SilkS")
			(effects
				(font
					(size 0.7874 0.5842)
					(thickness 0.1524)
				)
				(justify left)
			)
		)
		(property "Value" ""
			(at 0 0 0)
			(layer "F.Fab")
			(effects
				(font
					(size 1.27 1.27)
				)
			)
		)
		(duplicate_pad_numbers_are_jumpers no)
		(fp_line
			(start -2.500122 -2.999994)
			(end -2.24409 -2.999994)
			(stroke
				(width 0.1524)
				(type default)
			)
			(layer "F.SilkS")
		)
		(fp_line
			(start -2.500122 -2.529078)
			(end -2.500122 -2.999994)
			(stroke
				(width 0.1524)
				(type default)
			)
			(layer "F.SilkS")
		)
		(fp_line
			(start -2.500122 0.6604)
			(end -2.500122 0.229108)
			(stroke
				(width 0.1524)
				(type default)
			)
			(layer "F.SilkS")
		)
		(fp_line
			(start -2.500122 2.999994)
			(end -2.500122 2.339594)
			(stroke
				(width 0.1524)
				(type default)
			)
			(layer "F.SilkS")
		)
		(fp_line
			(start -2.2987 2.999994)
			(end -2.500122 2.999994)
			(stroke
				(width 0.1524)
				(type default)
			)
			(layer "F.SilkS")
		)
		(fp_line
			(start 2.31394 -2.999994)
			(end 2.500122 -2.999994)
			(stroke
				(width 0.1524)
				(type default)
			)
			(layer "F.SilkS")
		)
		(fp_line
			(start 2.500122 -2.999994)
			(end 2.500122 -2.44348)
			(stroke
				(width 0.1524)
				(type default)
			)
			(layer "F.SilkS")
		)
		(fp_line
			(start 2.500122 2.339594)
			(end 2.500122 2.999994)
			(stroke
				(width 0.1524)
				(type default)
			)
			(layer "F.SilkS")
		)
		(fp_line
			(start 2.500122 2.999994)
			(end 2.2987 2.999994)
			(stroke
				(width 0.1524)
				(type default)
			)
			(layer "F.SilkS")
		)
		(fp_poly
			(pts
				(xy -5.358892 -2.826258) (xy -4.342892 -2.318258) (xy -5.358892 -1.810258)
			)
			(stroke
				(width 0)
				(type default)
			)
			(fill yes)
			(layer "F.SilkS")
		)
		(fp_line
			(start -2.500122 -2.999994)
			(end 2.500122 -2.999994)
			(stroke
				(width 0.1)
				(type default)
			)
			(layer "F.Fab")
		)
		(fp_line
			(start -2.500122 2.999994)
			(end -2.500122 -2.999994)
			(stroke
				(width 0.1)
				(type default)
			)
			(layer "F.Fab")
		)
		(fp_line
			(start 2.500122 -2.999994)
			(end 2.500122 2.999994)
			(stroke
				(width 0.1)
				(type default)
			)
			(layer "F.Fab")
		)
		(fp_line
			(start 2.500122 2.999994)
			(end -2.500122 2.999994)
			(stroke
				(width 0.1)
				(type default)
			)
			(layer "F.Fab")
		)
		(fp_poly
			(pts
				(xy -4.218432 -2.783078) (xy -4.218432 -1.767078) (xy -3.202432 -2.275078)
			)
			(stroke
				(width 0)
				(type default)
			)
			(fill yes)
			(layer "F.Fab")
		)
		(pad "1" smd rect
			(at -2.400046 -2.275078 90)
			(size 0.2286 0.6096)
			(layers "F.Cu" "F.Mask" "F.Paste")
			(net "PVCCFA_EHV_FIVRA_CPU1_VOS3")
		)
		(pad "2" smd rect
			(at -2.400046 -1.82499 90)
			(size 0.2286 0.6096)
			(layers "F.Cu" "F.Mask" "F.Paste")
			(net "GND")
		)
		(pad "3" smd rect
			(at -2.400046 -1.374902 90)
			(size 0.2286 0.6096)
			(layers "F.Cu" "F.Mask" "F.Paste")
			(net "PVCCFA_EHV_FIVRA_CPU1_VDD3")
		)
		(pad "4" smd rect
			(at -2.400046 -0.925068 90)
			(size 0.2286 0.6096)
			(layers "F.Cu" "F.Mask" "F.Paste")
			(net "PVCCFA_EHV_FIVRA_CPU1_PVCC1")
		)
		(pad "5" smd rect
			(at -2.400046 -0.47498 90)
			(size 0.2286 0.6096)
			(layers "F.Cu" "F.Mask" "F.Paste")
			(net "GND")
		)
		(pad "6" smd rect
			(at -2.400046 -0.024892 90)
			(size 0.2286 0.6096)
			(layers "F.Cu" "F.Mask" "F.Paste")
			(net "Net_8499")
		)
		(pad "7_9-20_24" smd circle
			(at 0 1.150112 90)
			(size 0 0)
			(layers "F.Cu" "F.Mask" "F.Paste")
			(net "GND")
		)
		(pad "10_19" smd rect
			(at 0 2.899918 90)
			(size 0.6096 4.318)
			(layers "F.Cu" "F.Mask" "F.Paste")
			(net "SW_PVCCFA_EHV_FIVRA_CPU1_SW3")
		)
		(pad "25_29" smd rect
			(at 1.549908 -1.279906 270)
			(size 2.0574 2.3114)
			(layers "F.Cu" "F.Mask" "F.Paste")
			(net "SW_P12V_PVCCFA_EHV_FIVRA_CPU1_R")
		)
		(pad "30" smd rect
			(at 2.05994 -2.899918)
			(size 0.2286 0.6096)
			(layers "F.Cu" "F.Mask" "F.Paste")
			(net "SW_P12V_PVCCFA_EHV_FIVRA_CPU1_R")
		)
		(pad "31" smd rect
			(at 1.610106 -2.899918)
			(size 0.2286 0.6096)
			(layers "F.Cu" "F.Mask" "F.Paste")
			(net "Net_8500")
		)
		(pad "32" smd rect
			(at 1.160018 -2.899918)
			(size 0.2286 0.6096)
			(layers "F.Cu" "F.Mask" "F.Paste")
			(net "SW_PVCCFA_EHV_FIVRA_CPU1_BOOTR3")
		)
		(pad "33" smd rect
			(at 0.70993 -2.899918)
			(size 0.2286 0.6096)
			(layers "F.Cu" "F.Mask" "F.Paste")
			(net "SW_PVCCFA_EHV_FIVRA_CPU1_BOOT3")
		)
		(pad "34" smd rect
			(at 0.260096 -2.899918)
			(size 0.2286 0.6096)
			(layers "F.Cu" "F.Mask" "F.Paste")
			(net "PVCCFA_EHV_FIVRA_CPU1_PWM3")
		)
		(pad "35" smd rect
			(at -0.189992 -2.899918)
			(size 0.2286 0.6096)
			(layers "F.Cu" "F.Mask" "F.Paste")
			(net "PVCCFA_EHV_FIVRA_CPU1_VDD3")
		)
		(pad "36" smd rect
			(at -0.64008 -2.899918)
			(size 0.2286 0.6096)
			(layers "F.Cu" "F.Mask" "F.Paste")
			(net "PVCCFA_EHV_FIVRA_CPU1_BTSEN")
		)
		(pad "37" smd rect
			(at -1.089914 -2.899918)
			(size 0.2286 0.6096)
			(layers "F.Cu" "F.Mask" "F.Paste")
			(net "PVCCFA_EHV_FIVRA_CPU1_LSET3")
		)
		(pad "38" smd rect
			(at -1.540002 -2.899918)
			(size 0.2286 0.6096)
			(layers "F.Cu" "F.Mask" "F.Paste")
			(net "PVCCFA_EHV_FIVRA_CPU1_IMON3")
		)
		(pad "39" smd rect
			(at -1.99009 -2.899918)
			(size 0.2286 0.6096)
			(layers "F.Cu" "F.Mask" "F.Paste")
			(net "PVCCIN_CPU1_VREF")
		)
		(pad "40" smd rect
			(at -0.87503 -1.27508)
			(size 1.7526 1.9558)
			(layers "F.Cu" "F.Mask" "F.Paste")
			(net "GND")
		)
		(pad "41" smd rect
			(at -1.525016 0.249936 270)
			(size 0.3048 0.4572)
			(layers "F.Cu" "F.Mask" "F.Paste")
			(net "Net_8498")
		)
		(zone
			(layer "F.Cu")
			(hatch none 0.5)
			(connect_pads
				(clearance 0)
			)
			(min_thickness 0.25)
			(keepout
				(tracks not_allowed)
				(vias allowed)
				(pads allowed)
				(copperpour not_allowed)
				(footprints allowed)
			)
			(placement
				(enabled no)
				(sheetname "")
			)
			(fill
				(thermal_gap 0.5)
				(thermal_bridge_width 0.5)
				(island_removal_mode 0)
			)
			(polygon
				(pts
					(xy 179.212494 -350.55429) (xy 179.212494 -351.285048) (xy 184.212738 -351.285048) (xy 184.212738 -350.55429)
					(xy 183.922416 -350.55429) (xy 183.922416 -351.009966) (xy 179.502816 -351.009966) (xy 179.502816 -350.55429)
				)
			)
		)
		(zone
			(layer "F.Cu")
			(hatch none 0.5)
			(connect_pads
				(clearance 0)
			)
			(min_thickness 0.25)
			(keepout
				(tracks not_allowed)
				(vias allowed)
				(pads allowed)
				(copperpour not_allowed)
				(footprints allowed)
			)
			(placement
				(enabled no)
				(sheetname "")
			)
			(fill
				(thermal_gap 0.5)
				(thermal_bridge_width 0.5)
				(island_removal_mode 0)
			)
			(polygon
				(pts
					(xy 179.9336 -353.800664) (xy 180.70068 -353.800664) (xy 180.70068 -353.482148) (xy 180.761894 -353.482148)
					(xy 180.761894 -352.861118) (xy 180.70576 -352.804984) (xy 179.212494 -352.804984) (xy 179.212494 -353.261676)
					(xy 179.9082 -353.261676) (xy 179.9082 -353.101148) (xy 180.467 -353.101148) (xy 180.467 -353.507548)
					(xy 179.9082 -353.507548) (xy 179.9082 -353.287076) (xy 179.212494 -353.287076) (xy 179.212494 -353.414076)
					(xy 179.66817 -353.414076) (xy 179.66817 -353.784408) (xy 179.9336 -353.784408)
				)
			)
		)
	)
)
